(kicad_pcb
	(version 20260206)
	(generator "pcbnew")
	(generator_version "10.0")
	(general
		(thickness 1.6)
		(legacy_teardrops no)
	)
	(paper "A4")
	(title_block
		(title "peb — Lightning_PEB_BRD.brd")
		(comment 1 "Lightning (Wiwynn / Facebook NVMe JBOF) / footprint 41 of 2563 (GF8), pads 1-113 of 200")
	)
	(layers
		(0 "F.Cu" signal "TOP")
		(4 "In1.Cu" signal "L2GND")
		(6 "In2.Cu" signal "L3")
		(8 "In3.Cu" signal "L4VCC")
		(10 "In4.Cu" signal "L5VCC")
		(12 "In5.Cu" signal "L6")
		(14 "In6.Cu" signal "L7GND")
		(2 "B.Cu" signal "BOTTOM")
		(9 "F.Adhes" user "F.Adhesive")
		(11 "B.Adhes" user "B.Adhesive")
		(13 "F.Paste" user "Package Geometry/Pastemask Top")
		(15 "B.Paste" user "Package Geometry/Pastemask Bottom")
		(5 "F.SilkS" user "Ref Des/Silkscreen Top")
		(7 "B.SilkS" user "Ref Des/Silkscreen Bottom")
		(1 "F.Mask" user "Board Geometry/Soldermask Top")
		(3 "B.Mask" user "Board Geometry/Soldermask Bottom")
		(17 "Dwgs.User" user "User.Drawings")
		(19 "Cmts.User" user "User.Comments")
		(21 "Eco1.User" user "User.Eco1")
		(23 "Eco2.User" user "User.Eco2")
		(25 "Edge.Cuts" user "Board Geometry/Outline")
		(27 "Margin" user)
		(31 "F.CrtYd" user "Package Geometry/Place Bound Top")
		(29 "B.CrtYd" user "Package Geometry/Place Bound Bottom")
		(35 "F.Fab" user "Ref Des/Assembly Top")
		(33 "B.Fab" user "Ref Des/Assembly Bottom")
	)
	(footprint ""
		(layer "F.Cu")
		(at 75.300078 -226.70008 180)
		(property "Reference" "GF8"
			(at 0 0 180)
			(layer "F.SilkS")
			(hide yes)
			(effects
				(font
					(size 1.27 1.27)
				)
			)
		)
		(property "Value" "GF-200P-8-GP-U1"
			(at -43.1673 -7.6327 180)
			(unlocked yes)
			(layer "F.Fab")
			(hide yes)
			(effects
				(font
					(size 1.016 1.016)
					(thickness 0.1524)
				)
			)
		)
		(property "Device Type" "GF-200P-8-U1"
			(at -43.1673 -9.1567 180)
			(unlocked yes)
			(layer "F.Fab")
			(hide yes)
			(effects
				(font
					(size 1.016 1.016)
					(thickness 0.1524)
				)
			)
		)
		(duplicate_pad_numbers_are_jumpers no)
		(pad "A1" smd rect
			(at -36.399978 -1.1557 180)
			(size 0.5588 2.3114)
			(layers "F.Cu" "F.Mask" "F.Paste")
			(net "GND")
		)
		(pad "A2" smd rect
			(at -35.599878 -1.1557 180)
			(size 0.5588 2.3114)
			(layers "F.Cu" "F.Mask" "F.Paste")
			(net "PCIE_REFCLK_S1_N")
		)
		(pad "A3" smd rect
			(at -34.800032 -1.1557 180)
			(size 0.5588 2.3114)
			(layers "F.Cu" "F.Mask" "F.Paste")
			(net "PCIE_REFCLK_S1_P")
		)
		(pad "A4" smd rect
			(at -33.999932 -1.1557 180)
			(size 0.5588 2.3114)
			(layers "F.Cu" "F.Mask" "F.Paste")
			(net "GND")
		)
		(pad "A5" smd rect
			(at -33.200086 -1.1557 180)
			(size 0.5588 2.3114)
			(layers "F.Cu" "F.Mask" "F.Paste")
			(net "PCIE_TX_N60")
		)
		(pad "A6" smd rect
			(at -32.399986 -1.1557 180)
			(size 0.5588 2.3114)
			(layers "F.Cu" "F.Mask" "F.Paste")
			(net "PCIE_TX_P60")
		)
		(pad "A7" smd rect
			(at -31.599886 -1.1557 180)
			(size 0.5588 2.3114)
			(layers "F.Cu" "F.Mask" "F.Paste")
			(net "GND")
		)
		(pad "A8" smd rect
			(at -30.80004 -1.1557 180)
			(size 0.5588 2.3114)
			(layers "F.Cu" "F.Mask" "F.Paste")
			(net "GND")
		)
		(pad "A9" smd rect
			(at -29.99994 -1.1557 180)
			(size 0.5588 2.3114)
			(layers "F.Cu" "F.Mask" "F.Paste")
			(net "PCIE_TX_N61")
		)
		(pad "A10" smd rect
			(at -29.200094 -1.1557 180)
			(size 0.5588 2.3114)
			(layers "F.Cu" "F.Mask" "F.Paste")
			(net "PCIE_TX_P61")
		)
		(pad "A11" smd rect
			(at -28.399994 -1.1557 180)
			(size 0.5588 2.3114)
			(layers "F.Cu" "F.Mask" "F.Paste")
			(net "GND")
		)
		(pad "A12" smd rect
			(at -27.599894 -1.1557 180)
			(size 0.5588 2.3114)
			(layers "F.Cu" "F.Mask" "F.Paste")
			(net "GND")
		)
		(pad "A13" smd rect
			(at -26.800048 -1.1557 180)
			(size 0.5588 2.3114)
			(layers "F.Cu" "F.Mask" "F.Paste")
			(net "PCIE_TX_N62")
		)
		(pad "A14" smd rect
			(at -25.999948 -1.1557 180)
			(size 0.5588 2.3114)
			(layers "F.Cu" "F.Mask" "F.Paste")
			(net "PCIE_TX_P62")
		)
		(pad "A15" smd rect
			(at -25.200102 -1.1557 180)
			(size 0.5588 2.3114)
			(layers "F.Cu" "F.Mask" "F.Paste")
			(net "GND")
		)
		(pad "A16" smd rect
			(at -24.400002 -1.1557 180)
			(size 0.5588 2.3114)
			(layers "F.Cu" "F.Mask" "F.Paste")
			(net "GND")
		)
		(pad "A17" smd rect
			(at -23.599902 -1.1557 180)
			(size 0.5588 2.3114)
			(layers "F.Cu" "F.Mask" "F.Paste")
			(net "PCIE_TX_N63")
		)
		(pad "A18" smd rect
			(at -22.800056 -1.1557 180)
			(size 0.5588 2.3114)
			(layers "F.Cu" "F.Mask" "F.Paste")
			(net "PCIE_TX_P63")
		)
		(pad "A19" smd rect
			(at -21.999956 -1.1557 180)
			(size 0.5588 2.3114)
			(layers "F.Cu" "F.Mask" "F.Paste")
			(net "GND")
		)
		(pad "A20" smd rect
			(at -21.20011 -1.1557 180)
			(size 0.5588 2.3114)
			(layers "F.Cu" "F.Mask" "F.Paste")
			(net "SSD_PRSNT#1_R")
		)
		(pad "A21" smd rect
			(at -20.40001 -1.1557 180)
			(size 0.5588 2.3114)
			(layers "F.Cu" "F.Mask" "F.Paste")
			(net "SSD_ATNLED#1_R")
		)
		(pad "A22" smd rect
			(at -19.59991 -1.1557 180)
			(size 0.5588 2.3114)
			(layers "F.Cu" "F.Mask" "F.Paste")
			(net "SSD_PWREN1_R")
		)
		(pad "A23" smd rect
			(at -18.800064 -1.1557 180)
			(size 0.5588 2.3114)
			(layers "F.Cu" "F.Mask" "F.Paste")
			(net "GND")
		)
		(pad "A24" smd rect
			(at -17.999964 -1.1557 180)
			(size 0.5588 2.3114)
			(layers "F.Cu" "F.Mask" "F.Paste")
			(net "PCIE_TX_N64")
		)
		(pad "A25" smd rect
			(at -17.200118 -1.1557 180)
			(size 0.5588 2.3114)
			(layers "F.Cu" "F.Mask" "F.Paste")
			(net "PCIE_TX_P64")
		)
		(pad "A26" smd rect
			(at -16.400018 -1.1557 180)
			(size 0.5588 2.3114)
			(layers "F.Cu" "F.Mask" "F.Paste")
			(net "GND")
		)
		(pad "A27" smd rect
			(at -15.599918 -1.1557 180)
			(size 0.5588 2.3114)
			(layers "F.Cu" "F.Mask" "F.Paste")
			(net "GND")
		)
		(pad "A28" smd rect
			(at -14.800072 -1.1557 180)
			(size 0.5588 2.3114)
			(layers "F.Cu" "F.Mask" "F.Paste")
			(net "PCIE_TX_N65")
		)
		(pad "A29" smd rect
			(at -13.999972 -1.1557 180)
			(size 0.5588 2.3114)
			(layers "F.Cu" "F.Mask" "F.Paste")
			(net "PCIE_TX_P65")
		)
		(pad "A30" smd rect
			(at -13.200126 -1.1557 180)
			(size 0.5588 2.3114)
			(layers "F.Cu" "F.Mask" "F.Paste")
			(net "GND")
		)
		(pad "A31" smd rect
			(at -12.400026 -1.1557 180)
			(size 0.5588 2.3114)
			(layers "F.Cu" "F.Mask" "F.Paste")
			(net "GND")
		)
		(pad "A32" smd rect
			(at -11.599926 -1.1557 180)
			(size 0.5588 2.3114)
			(layers "F.Cu" "F.Mask" "F.Paste")
			(net "PCIE_TX_N66")
		)
		(pad "A33" smd rect
			(at -10.80008 -1.1557 180)
			(size 0.5588 2.3114)
			(layers "F.Cu" "F.Mask" "F.Paste")
			(net "PCIE_TX_P66")
		)
		(pad "A34" smd rect
			(at -9.99998 -1.1557 180)
			(size 0.5588 2.3114)
			(layers "F.Cu" "F.Mask" "F.Paste")
			(net "GND")
		)
		(pad "A35" smd rect
			(at -9.19988 -1.1557 180)
			(size 0.5588 2.3114)
			(layers "F.Cu" "F.Mask" "F.Paste")
			(net "GND")
		)
		(pad "A36" smd rect
			(at -8.400034 -1.1557 180)
			(size 0.5588 2.3114)
			(layers "F.Cu" "F.Mask" "F.Paste")
			(net "PCIE_TX_N67")
		)
		(pad "A37" smd rect
			(at -7.599934 -1.1557 180)
			(size 0.5588 2.3114)
			(layers "F.Cu" "F.Mask" "F.Paste")
			(net "PCIE_TX_P67")
		)
		(pad "A38" smd rect
			(at -6.800088 -1.1557 180)
			(size 0.5588 2.3114)
			(layers "F.Cu" "F.Mask" "F.Paste")
			(net "GND")
		)
		(pad "A39" smd rect
			(at -5.999988 -1.1557 180)
			(size 0.5588 2.3114)
			(layers "F.Cu" "F.Mask" "F.Paste")
			(net "GND")
		)
		(pad "A40" smd rect
			(at -5.199888 -1.1557 180)
			(size 0.5588 2.3114)
			(layers "F.Cu" "F.Mask" "F.Paste")
			(net "PCIE_TX_N68")
		)
		(pad "A41" smd rect
			(at -4.400042 -1.1557 180)
			(size 0.5588 2.3114)
			(layers "F.Cu" "F.Mask" "F.Paste")
			(net "PCIE_TX_P68")
		)
		(pad "A42" smd rect
			(at -3.599942 -1.1557 180)
			(size 0.5588 2.3114)
			(layers "F.Cu" "F.Mask" "F.Paste")
			(net "GND")
		)
		(pad "A43" smd rect
			(at -2.800096 -1.1557 180)
			(size 0.5588 2.3114)
			(layers "F.Cu" "F.Mask" "F.Paste")
			(net "SSD_PERST#1_R")
		)
		(pad "A44" smd rect
			(at -1.999996 -1.1557 180)
			(size 0.5588 2.3114)
			(layers "F.Cu" "F.Mask" "F.Paste")
			(net "SSD_PERST#0_R")
		)
		(pad "A45" smd rect
			(at 1.999996 -1.1557 180)
			(size 0.5588 2.3114)
			(layers "F.Cu" "F.Mask" "F.Paste")
			(net "PWM_EXP_A")
		)
		(pad "A46" smd rect
			(at 2.800096 -1.1557 180)
			(size 0.5588 1.8796)
			(drill
				(offset 0 -0.2159)
			)
			(layers "F.Cu" "F.Mask" "F.Paste")
			(net "PCIE_MATED#_A")
		)
		(pad "A47" smd rect
			(at 3.599942 -1.1557 180)
			(size 0.5588 2.3114)
			(layers "F.Cu" "F.Mask" "F.Paste")
			(net "GND")
		)
		(pad "A48" smd rect
			(at 4.400042 -1.1557 180)
			(size 0.5588 2.3114)
			(layers "F.Cu" "F.Mask" "F.Paste")
			(net "PCIE_TX_N69")
		)
		(pad "A49" smd rect
			(at 5.199888 -1.1557 180)
			(size 0.5588 2.3114)
			(layers "F.Cu" "F.Mask" "F.Paste")
			(net "PCIE_TX_P69")
		)
		(pad "A50" smd rect
			(at 5.999988 -1.1557 180)
			(size 0.5588 2.3114)
			(layers "F.Cu" "F.Mask" "F.Paste")
			(net "GND")
		)
		(pad "A51" smd rect
			(at 6.800088 -1.1557 180)
			(size 0.5588 2.3114)
			(layers "F.Cu" "F.Mask" "F.Paste")
			(net "GND")
		)
		(pad "A52" smd rect
			(at 7.599934 -1.1557 180)
			(size 0.5588 2.3114)
			(layers "F.Cu" "F.Mask" "F.Paste")
			(net "PCIE_TX_N70")
		)
		(pad "A53" smd rect
			(at 8.400034 -1.1557 180)
			(size 0.5588 2.3114)
			(layers "F.Cu" "F.Mask" "F.Paste")
			(net "PCIE_TX_P70")
		)
		(pad "A54" smd rect
			(at 9.19988 -1.1557 180)
			(size 0.5588 2.3114)
			(layers "F.Cu" "F.Mask" "F.Paste")
			(net "GND")
		)
		(pad "A55" smd rect
			(at 9.99998 -1.1557 180)
			(size 0.5588 2.3114)
			(layers "F.Cu" "F.Mask" "F.Paste")
			(net "GND")
		)
		(pad "A56" smd rect
			(at 10.80008 -1.1557 180)
			(size 0.5588 2.3114)
			(layers "F.Cu" "F.Mask" "F.Paste")
			(net "PCIE_TX_N71")
		)
		(pad "A57" smd rect
			(at 11.599926 -1.1557 180)
			(size 0.5588 2.3114)
			(layers "F.Cu" "F.Mask" "F.Paste")
			(net "PCIE_TX_P71")
		)
		(pad "A58" smd rect
			(at 12.400026 -1.1557 180)
			(size 0.5588 2.3114)
			(layers "F.Cu" "F.Mask" "F.Paste")
			(net "GND")
		)
		(pad "A59" smd rect
			(at 13.200126 -1.1557 180)
			(size 0.5588 2.3114)
			(layers "F.Cu" "F.Mask" "F.Paste")
			(net "SSD_PWREN0_R")
		)
		(pad "A60" smd rect
			(at 13.999972 -1.1557 180)
			(size 0.5588 2.3114)
			(layers "F.Cu" "F.Mask" "F.Paste")
			(net "SSD_ATNLED#0_R")
		)
		(pad "A61" smd rect
			(at 14.800072 -1.1557 180)
			(size 0.5588 2.3114)
			(layers "F.Cu" "F.Mask" "F.Paste")
			(net "SSD_PRSNT#0_R")
		)
		(pad "A62" smd rect
			(at 15.599918 -1.1557 180)
			(size 0.5588 2.3114)
			(layers "F.Cu" "F.Mask" "F.Paste")
			(net "GND")
		)
		(pad "A63" smd rect
			(at 16.400018 -1.1557 180)
			(size 0.5588 2.3114)
			(layers "F.Cu" "F.Mask" "F.Paste")
			(net "PCIE_TX_N72")
		)
		(pad "A64" smd rect
			(at 17.200118 -1.1557 180)
			(size 0.5588 2.3114)
			(layers "F.Cu" "F.Mask" "F.Paste")
			(net "PCIE_TX_P72")
		)
		(pad "A65" smd rect
			(at 17.999964 -1.1557 180)
			(size 0.5588 2.3114)
			(layers "F.Cu" "F.Mask" "F.Paste")
			(net "GND")
		)
		(pad "A66" smd rect
			(at 18.800064 -1.1557 180)
			(size 0.5588 2.3114)
			(layers "F.Cu" "F.Mask" "F.Paste")
			(net "GND")
		)
		(pad "A67" smd rect
			(at 19.59991 -1.1557 180)
			(size 0.5588 2.3114)
			(layers "F.Cu" "F.Mask" "F.Paste")
			(net "PCIE_TX_N73")
		)
		(pad "A68" smd rect
			(at 20.40001 -1.1557 180)
			(size 0.5588 2.3114)
			(layers "F.Cu" "F.Mask" "F.Paste")
			(net "PCIE_TX_P73")
		)
		(pad "A69" smd rect
			(at 21.20011 -1.1557 180)
			(size 0.5588 2.3114)
			(layers "F.Cu" "F.Mask" "F.Paste")
			(net "GND")
		)
		(pad "A70" smd rect
			(at 21.999956 -1.1557 180)
			(size 0.5588 2.3114)
			(layers "F.Cu" "F.Mask" "F.Paste")
			(net "GND")
		)
		(pad "A71" smd rect
			(at 22.800056 -1.1557 180)
			(size 0.5588 2.3114)
			(layers "F.Cu" "F.Mask" "F.Paste")
			(net "PCIE_TX_N74")
		)
		(pad "A72" smd rect
			(at 23.599902 -1.1557 180)
			(size 0.5588 2.3114)
			(layers "F.Cu" "F.Mask" "F.Paste")
			(net "PCIE_TX_P74")
		)
		(pad "A73" smd rect
			(at 24.400002 -1.1557 180)
			(size 0.5588 2.3114)
			(layers "F.Cu" "F.Mask" "F.Paste")
			(net "GND")
		)
		(pad "A74" smd rect
			(at 25.200102 -1.1557 180)
			(size 0.5588 2.3114)
			(layers "F.Cu" "F.Mask" "F.Paste")
			(net "GND")
		)
		(pad "A75" smd rect
			(at 25.999948 -1.1557 180)
			(size 0.5588 2.3114)
			(layers "F.Cu" "F.Mask" "F.Paste")
			(net "PCIE_TX_N75")
		)
		(pad "A76" smd rect
			(at 26.800048 -1.1557 180)
			(size 0.5588 2.3114)
			(layers "F.Cu" "F.Mask" "F.Paste")
			(net "PCIE_TX_P75")
		)
		(pad "A77" smd rect
			(at 27.599894 -1.1557 180)
			(size 0.5588 2.3114)
			(layers "F.Cu" "F.Mask" "F.Paste")
			(net "GND")
		)
		(pad "A78" smd rect
			(at 28.399994 -1.1557 180)
			(size 0.5588 2.3114)
			(layers "F.Cu" "F.Mask" "F.Paste")
			(net "PCIE_REFCLK_S4_P")
		)
		(pad "A79" smd rect
			(at 29.200094 -1.1557 180)
			(size 0.5588 2.3114)
			(layers "F.Cu" "F.Mask" "F.Paste")
			(net "PCIE_REFCLK_S4_N")
		)
		(pad "A80" smd rect
			(at 29.99994 -1.1557 180)
			(size 0.5588 2.3114)
			(layers "F.Cu" "F.Mask" "F.Paste")
			(net "GND")
		)
		(pad "A81" smd rect
			(at 30.80004 -1.1557 180)
			(size 0.5588 2.3114)
			(layers "F.Cu" "F.Mask" "F.Paste")
			(net "BUF_I2C7_B_DBP_SCL")
		)
		(pad "A82" smd rect
			(at 31.599886 -1.1557 180)
			(size 0.5588 2.3114)
			(layers "F.Cu" "F.Mask" "F.Paste")
			(net "BUF_I2C7_B_DPB_SDA")
		)
		(pad "A83" smd rect
			(at 32.399986 -1.1557 180)
			(size 0.5588 2.3114)
			(layers "F.Cu" "F.Mask" "F.Paste")
			(net "GND")
		)
		(pad "A84" smd rect
			(at 33.200086 -1.1557 180)
			(size 0.5588 2.3114)
			(layers "F.Cu" "F.Mask" "F.Paste")
			(net "BUF_I2C9_CLKBUF2_SCL")
		)
		(pad "A85" smd rect
			(at 33.999932 -1.1557 180)
			(size 0.5588 2.3114)
			(layers "F.Cu" "F.Mask" "F.Paste")
			(net "BUF_I2C9_CLKBUF2_SDA")
		)
		(pad "A86" smd rect
			(at 34.800032 -1.1557 180)
			(size 0.5588 2.3114)
			(layers "F.Cu" "F.Mask" "F.Paste")
			(net "GND")
		)
		(pad "A87" smd rect
			(at 35.599878 -1.1557 180)
			(size 0.5588 2.3114)
			(layers "F.Cu" "F.Mask" "F.Paste")
			(net "BUF_I2C6_C_FCB_SCL")
		)
		(pad "A88" smd rect
			(at 36.399978 -1.1557 180)
			(size 0.5588 2.3114)
			(layers "F.Cu" "F.Mask" "F.Paste")
			(net "BUF_I2C6_C_FCB_SDA")
		)
		(pad "A89" smd rect
			(at 37.200078 -1.1557 180)
			(size 0.5588 2.3114)
			(layers "F.Cu" "F.Mask" "F.Paste")
			(net "GND")
		)
		(pad "A90" smd rect
			(at 37.999924 -1.1557 180)
			(size 0.5588 2.3114)
			(layers "F.Cu" "F.Mask" "F.Paste")
			(net "GND")
		)
		(pad "A91" smd rect
			(at 38.800024 -1.1557 180)
			(size 0.5588 2.3114)
			(layers "F.Cu" "F.Mask" "F.Paste")
			(net "GND")
		)
		(pad "A92" smd rect
			(at 39.600124 -1.1557 180)
			(size 0.5588 2.3114)
			(layers "F.Cu" "F.Mask" "F.Paste")
			(net "GND")
		)
		(pad "A93" smd rect
			(at 40.39997 -1.1557 180)
			(size 0.5588 2.3114)
			(layers "F.Cu" "F.Mask" "F.Paste")
			(net "GND")
		)
		(pad "A94" smd rect
			(at 41.20007 -1.1557 180)
			(size 0.5588 2.3114)
			(layers "F.Cu" "F.Mask" "F.Paste")
			(net "GND")
		)
		(pad "A95" smd rect
			(at 41.999916 -1.1557 180)
			(size 0.5588 2.3114)
			(layers "F.Cu" "F.Mask" "F.Paste")
			(net "P12V_PCIE")
		)
		(pad "A96" smd rect
			(at 42.800016 -1.1557 180)
			(size 0.5588 2.3114)
			(layers "F.Cu" "F.Mask" "F.Paste")
			(net "P12V_PCIE")
		)
		(pad "A97" smd rect
			(at 43.600116 -1.1557 180)
			(size 0.5588 2.3114)
			(layers "F.Cu" "F.Mask" "F.Paste")
			(net "P12V_PCIE")
		)
		(pad "A98" smd rect
			(at 44.399962 -1.1557 180)
			(size 0.5588 2.3114)
			(layers "F.Cu" "F.Mask" "F.Paste")
			(net "P12V_PCIE")
		)
		(pad "A99" smd rect
			(at 45.200062 -1.1557 180)
			(size 0.5588 2.3114)
			(layers "F.Cu" "F.Mask" "F.Paste")
			(net "P12V_PCIE")
		)
		(pad "A100" smd rect
			(at 45.999908 -1.1557 180)
			(size 0.5588 1.8796)
			(drill
				(offset 0 -0.2159)
			)
			(layers "F.Cu" "F.Mask" "F.Paste")
			(net "P12V_PCIE")
		)
		(pad "B1" smd rect
			(at -36.399978 -0.7747 180)
			(size 0.5588 2.3114)
			(drill
				(offset 0 -0.381)
			)
			(layers "F.Cu" "F.Mask" "F.Paste")
			(net "GND")
		)
		(pad "B2" smd rect
			(at -35.599878 -0.7747 180)
			(size 0.5588 2.3114)
			(drill
				(offset 0 -0.381)
			)
			(layers "F.Cu" "F.Mask" "F.Paste")
			(net "PCIE_REFCLK_S2_P")
		)
		(pad "B3" smd rect
			(at -34.800032 -0.7747 180)
			(size 0.5588 2.3114)
			(drill
				(offset 0 -0.381)
			)
			(layers "F.Cu" "F.Mask" "F.Paste")
			(net "PCIE_REFCLK_S2_N")
		)
		(pad "B4" smd rect
			(at -33.999932 -0.7747 180)
			(size 0.5588 2.3114)
			(drill
				(offset 0 -0.381)
			)
			(layers "F.Cu" "F.Mask" "F.Paste")
			(net "GND")
		)
		(pad "B5" smd rect
			(at -33.200086 -0.7747 180)
			(size 0.5588 2.3114)
			(drill
				(offset 0 -0.381)
			)
			(layers "F.Cu" "F.Mask" "F.Paste")
			(net "SSD_PERST#10_R")
		)
		(pad "B6" smd rect
			(at -32.399986 -0.7747 180)
			(size 0.5588 2.3114)
			(drill
				(offset 0 -0.381)
			)
			(layers "F.Cu" "F.Mask" "F.Paste")
			(net "GND")
		)
		(pad "B7" smd rect
			(at -31.599886 -0.7747 180)
			(size 0.5588 2.3114)
			(drill
				(offset 0 -0.381)
			)
			(layers "F.Cu" "F.Mask" "F.Paste")
			(net "PCIE_RX_N60")
		)
		(pad "B8" smd rect
			(at -30.80004 -0.7747 180)
			(size 0.5588 2.3114)
			(drill
				(offset 0 -0.381)
			)
			(layers "F.Cu" "F.Mask" "F.Paste")
			(net "PCIE_RX_P60")
		)
		(pad "B9" smd rect
			(at -29.99994 -0.7747 180)
			(size 0.5588 2.3114)
			(drill
				(offset 0 -0.381)
			)
			(layers "F.Cu" "F.Mask" "F.Paste")
			(net "GND")
		)
		(pad "B10" smd rect
			(at -29.200094 -0.7747 180)
			(size 0.5588 2.3114)
			(drill
				(offset 0 -0.381)
			)
			(layers "F.Cu" "F.Mask" "F.Paste")
			(net "GND")
		)
		(pad "B11" smd rect
			(at -28.399994 -0.7747 180)
			(size 0.5588 2.3114)
			(drill
				(offset 0 -0.381)
			)
			(layers "F.Cu" "F.Mask" "F.Paste")
			(net "PCIE_RX_N61")
		)
		(pad "B12" smd rect
			(at -27.599894 -0.7747 180)
			(size 0.5588 2.3114)
			(drill
				(offset 0 -0.381)
			)
			(layers "F.Cu" "F.Mask" "F.Paste")
			(net "PCIE_RX_P61")
		)
		(pad "B13" smd rect
			(at -26.800048 -0.7747 180)
			(size 0.5588 2.3114)
			(drill
				(offset 0 -0.381)
			)
			(layers "F.Cu" "F.Mask" "F.Paste")
			(net "GND")
		)
	)
)
